FILE_TYPE = CONNECTIVITY;
{Allegro Design Entry HDL 16.6-p007 (v16-6-112F) 10/10/2012}
"PAGE_NUMBER" = 77;
0"NC";
1"M_G_DQS_DN<17:0>";
2"M_G_DQS_DP<17:0>";
3"M_G_DQ<63:0>";
4"M_G_CLK_DP<3:0>";
5"M_G_CLK_DN<3:0>";
6"M_G_CS_N<7:0>";
7"M_G_MA<17:0>";
8"M_G_ECC<7:0>";
9"M_G_BG<1:0>";
10"M_G_BA<1:0>";
11"M_G_ODT<3:0>";
12"M_G_CKE<3:0>";
13"PVDDQ_GHJ\g";
14"PVTT_GHJ\g";
15"GND\g";
16"GND\g";
17"GND\g";
18"PVPP_GHJ\g";
19"PVPP_GHJ\g";
20"P12V_NVDIMM_GHJ\g";
21"GND\g";
22"M_G_VREF";
23"TP_CH_G_DIMM_G0_RFU_1";
24"TP_CH_G_DIMM_G0_RFU_2";
25"M_G_ECC<1>";
26"TP_CH_G_DIMM_G0_RFU_0";
27"M_G_ACT_N";
28"M_G_ALERT_N";
29"SMB_DDR_GHJ_VPP_SDA";
30"SMB_DDR_GHJ_VPP_SCL";
31"FM_ADR_COMPLETE_GHJ_N";
32"FM_DIMM_EVENT_COD_N";
33"M_G_PAR";
34"M_GHJ_RST_N";
35"M_G_CS_N<0>";
36"M_G_CKE<0>";
37"M_G_ODT<1>";
38"M_G_ODT<0>";
39"M_G_ECC<6>";
40"M_G_MA<10>";
41"M_G_MA<2>";
42"M_G_BA<0>";
43"M_G_BG<1>";
44"M_G_BG<0>";
45"M_G_CLK_DP<1>";
46"M_G_CKE<1>";
47"M_G_ECC<0>";
48"M_G_ECC<3>";
49"M_G_ECC<2>";
50"M_G_ECC<5>";
51"M_G_ECC<4>";
52"M_G_ECC<7>";
53"M_G_MA<9>";
54"M_G_MA<8>";
55"M_G_MA<7>";
56"M_G_MA<6>";
57"M_G_MA<5>";
58"M_G_MA<4>";
59"M_G_MA<3>";
60"M_G_MA<1>";
61"M_G_MA<0>";
62"M_G_CS_N<1>";
63"M_G_CS_N<2>";
64"M_G_CS_N<3>";
65"M_G_BA<1>";
66"M_G_CLK_DN<0>";
67"M_G_CLK_DP<0>";
68"M_G_CLK_DN<1>";
69"M_G_C<2>";
70"M_G_DQ<5>";
71"M_G_DQ<2>";
72"M_G_DQ<3>";
73"M_G_DQ<1>";
74"M_G_DQ<0>";
75"M_G_DQ<4>";
76"M_G_DQ<14>";
77"M_G_DQ<7>";
78"M_G_DQ<9>";
79"M_G_DQ<8>";
80"M_G_DQ<11>";
81"M_G_DQ<10>";
82"M_G_DQ<13>";
83"M_G_DQ<12>";
84"M_G_DQ<15>";
85"M_G_DQ<6>";
86"M_G_DQ<19>";
87"M_G_DQ<18>";
88"M_G_DQ<21>";
89"M_G_DQ<20>";
90"M_G_DQ<23>";
91"M_G_DQ<22>";
92"M_G_DQ<25>";
93"M_G_DQ<24>";
94"M_G_DQ<17>";
95"M_G_DQ<16>";
96"M_G_DQ<27>";
97"M_G_DQ<34>";
98"M_G_DQ<31>";
99"M_G_DQ<30>";
100"M_G_DQ<33>";
101"M_G_DQ<32>";
102"M_G_DQ<35>";
103"M_G_DQ<29>";
104"M_G_DQ<28>";
105"M_G_DQ<26>";
106"M_G_DQ<39>";
107"M_G_DQ<37>";
108"M_G_DQ<36>";
109"M_G_DQ<41>";
110"M_G_DQ<43>";
111"M_G_DQ<44>";
112"M_G_DQ<47>";
113"M_G_DQ<45>";
114"M_G_DQ<42>";
115"M_G_DQ<40>";
116"M_G_DQ<38>";
117"M_G_DQ<46>";
118"M_G_DQ<50>";
119"M_G_DQ<53>";
120"M_G_DQ<52>";
121"M_G_DQ<55>";
122"M_G_DQ<54>";
123"M_G_DQ<57>";
124"M_G_DQ<51>";
125"M_G_DQ<48>";
126"M_G_DQ<49>";
127"M_G_MA<16>";
128"M_G_MA<15>";
129"M_G_MA<14>";
130"M_G_MA<11>";
131"M_G_MA<17>";
132"M_G_MA<13>";
133"M_G_MA<12>";
134"M_G_DQ<62>";
135"M_G_DQ<63>";
136"M_G_DQ<60>";
137"M_G_DQ<59>";
138"M_G_DQ<56>";
139"M_G_DQ<58>";
140"M_G_DQ<61>";
141"M_G_DQS_DP<7>";
142"M_G_DQS_DN<7>";
143"M_G_DQS_DP<6>";
144"M_G_DQS_DN<6>";
145"M_G_DQS_DP<5>";
146"M_G_DQS_DN<5>";
147"M_G_DQS_DP<4>";
148"M_G_DQS_DN<4>";
149"M_G_DQS_DP<3>";
150"M_G_DQS_DN<3>";
151"M_G_DQS_DP<2>";
152"M_G_DQS_DN<2>";
153"M_G_DQS_DP<1>";
154"M_G_DQS_DN<1>";
155"M_G_DQS_DP<0>";
156"M_G_DQS_DN<0>";
157"M_G_DQS_DP<17>";
158"M_G_DQS_DP<9>";
159"M_G_DQS_DN<9>";
160"M_G_DQS_DP<8>";
161"M_G_DQS_DN<8>";
162"M_G_DQS_DN<17>";
163"M_G_DQS_DP<16>";
164"M_G_DQS_DN<16>";
165"M_G_DQS_DP<15>";
166"M_G_DQS_DN<15>";
167"M_G_DQS_DP<14>";
168"M_G_DQS_DN<14>";
169"M_G_DQS_DP<13>";
170"M_G_DQS_DN<13>";
171"M_G_DQS_DP<12>";
172"M_G_DQS_DN<12>";
173"M_G_DQS_DP<11>";
174"M_G_DQS_DN<11>";
175"M_G_DQS_DP<10>";
176"M_G_DQS_DN<10>";
%"TAP"
"6","(700,4750)","2","mstr_standard","I10";
;
HDL_TAP"TRUE"
BODY_TYPE"PLUMBING"
CDS_LIB"mstr_standard";
"B \NAC \NWC"2;
"S \NAC"
BN"14"167;
%"TAP"
"6","(-1625,1775)","2","mstr_standard","I100";
;
HDL_TAP"TRUE"
BODY_TYPE"PLUMBING"
CDS_LIB"mstr_standard";
"B \NAC \NWC"3;
"S \NAC"
BN"11"80;
%"TAP"
"6","(-1625,1725)","2","mstr_standard","I101";
;
HDL_TAP"TRUE"
BODY_TYPE"PLUMBING"
CDS_LIB"mstr_standard";
"B \NAC \NWC"3;
"S \NAC"
BN"8"79;
%"TAP"
"6","(-1625,1675)","2","mstr_standard","I102";
;
HDL_TAP"TRUE"
BODY_TYPE"PLUMBING"
CDS_LIB"mstr_standard";
"B \NAC \NWC"3;
"S \NAC"
BN"9"78;
%"TAP"
"6","(-1625,1575)","2","mstr_standard","I103";
;
HDL_TAP"TRUE"
BODY_TYPE"PLUMBING"
CDS_LIB"mstr_standard";
"B \NAC \NWC"3;
"S \NAC"
BN"7"77;
%"TAP"
"6","(-1625,1625)","2","mstr_standard","I104";
;
HDL_TAP"TRUE"
BODY_TYPE"PLUMBING"
CDS_LIB"mstr_standard";
"B \NAC \NWC"3;
"S \NAC"
BN"6"85;
%"TAP"
"6","(-1625,1425)","2","mstr_standard","I105";
;
HDL_TAP"TRUE"
BODY_TYPE"PLUMBING"
CDS_LIB"mstr_standard";
"B \NAC \NWC"3;
"S \NAC"
BN"2"71;
%"TAP"
"6","(-1625,1475)","2","mstr_standard","I106";
;
HDL_TAP"TRUE"
BODY_TYPE"PLUMBING"
CDS_LIB"mstr_standard";
"B \NAC \NWC"3;
"S \NAC"
BN"5"70;
%"TAP"
"6","(-1625,1525)","2","mstr_standard","I107";
;
HDL_TAP"TRUE"
BODY_TYPE"PLUMBING"
CDS_LIB"mstr_standard";
"B \NAC \NWC"3;
"S \NAC"
BN"4"75;
%"TAP"
"6","(-1625,1325)","2","mstr_standard","I108";
;
HDL_TAP"TRUE"
BODY_TYPE"PLUMBING"
CDS_LIB"mstr_standard";
"B \NAC \NWC"3;
"S \NAC"
BN"0"74;
%"TAP"
"6","(-1625,1275)","2","mstr_standard","I109";
;
HDL_TAP"TRUE"
BODY_TYPE"PLUMBING"
CDS_LIB"mstr_standard";
"B \NAC \NWC"3;
"S \NAC"
BN"1"73;
%"TAP"
"6","(700,4850)","2","mstr_standard","I11";
;
HDL_TAP"TRUE"
BODY_TYPE"PLUMBING"
CDS_LIB"mstr_standard";
"B \NAC \NWC"2;
"S \NAC"
BN"15"165;
%"TAP"
"6","(-1625,1375)","2","mstr_standard","I110";
;
HDL_TAP"TRUE"
BODY_TYPE"PLUMBING"
CDS_LIB"mstr_standard";
"B \NAC \NWC"3;
"S \NAC"
BN"3"72;
%"SCONN288_H44441004"
"1","(-2375,2775)","0","mstr_sconn","I111";
;
CDS_SEC"1"
ROOM"DDR4_CH_G"
CDS_LOCATION"J1G1"
SEC"1"
SEC_TYPE"PIP"
CDS_LIB"mstr_sconn"
BOM_COST"MEM"
PACK_TYPE"PIP"
MATERIAL"SCONN"
PART_NUMBER"H44441-004"
LOCATION"J1G1";
"DQ<63>"
$PN"280"134;
"DQ<62>"
$PN"135"135;
"DQ<61>"
$PN"273"136;
"DQ<5>"
$PN"148"75;
"DQ<4>"
$PN"3"70;
"DQ<3>"
$PN"157"71;
"DQ<2>"
$PN"12"72;
"DQ<47>"
$PN"258"117;
"DQ<48>"
$PN"119"126;
"DQ<49>"
$PN"264"125;
"DQ<50>"
$PN"126"124;
"DQ<51>"
$PN"271"118;
"DQ<52>"
$PN"117"119;
"DQ<53>"
$PN"262"120;
"DQ<54>"
$PN"124"121;
"DQ<58>"
$PN"137"137;
"DQ<57>"
$PN"275"138;
"SAVE_N_NC"
$PN"230"31;
"RFU<1>"
$PN"227"23;
"RFU<0>"
$PN"205"26;
"DQ<17>"
$PN"172"95;
"DQ<15>"
$PN"166"76;
"DQ<26>"
$PN"45"96;
"DQ<27>"
$PN"190"105;
"S0_N"
$PN"84"35;
"CKE<0>"
$PN"60"36;
"ODT<1>"
$PN"91"37;
"ODT<0>"
$PN"87"38;
"CB<7>"
$PN"199"39;
"A16_RAS_N"
$PN"82"127;
"A15_CAS_N"
$PN"86"128;
"A14_WE_N"
$PN"228"129;
"A11"
$PN"210"130;
"A10"
$PN"225"40;
"DQ<38>"
$PN"102"106;
"DQ<36>"
$PN"95"107;
"DQ<35>"
$PN"249"97;
"A2"
$PN"216"41;
"ALERT_N"
$PN"208"28;
"ACT_N"
$PN"62"27;
"DQ<0>"
$PN"5"73;
"DQ<1>"
$PN"150"74;
"SA<1>"
$PN"140"16;
"SA<2>"
$PN"238"16;
"VDDSPD"
$PN"284"19;
"SA<0>"
$PN"139"16;
"BA<0>"
$PN"81"42;
"BG<1>"
$PN"207"43;
"BG<0>"
$PN"63"44;
"CK1P"
$PN"218"45;
"VREFCA"
$PN"146"22;
"SDA"
$PN"285"29;
"SCL"
$PN"141"30;
"RFU<2>"
$PN"144"24;
"RESET_N"
$PN"58"34;
"PAR"
$PN"222"33;
"EVENT_N"
$PN"78"32;
"DQ<6>"
$PN"10"77;
"DQ<7>"
$PN"155"85;
"DQ<8>"
$PN"16"78;
"DQ<9>"
$PN"161"79;
"DQ<10>"
$PN"23"80;
"DQ<11>"
$PN"168"81;
"DQ<12>"
$PN"14"82;
"DQ<13>"
$PN"159"83;
"DQ<14>"
$PN"21"84;
"DQ<16>"
$PN"27"94;
"DQ<18>"
$PN"34"86;
"DQ<19>"
$PN"179"87;
"DQ<20>"
$PN"25"88;
"DQ<21>"
$PN"170"89;
"DQ<22>"
$PN"32"90;
"DQ<23>"
$PN"177"91;
"DQ<24>"
$PN"38"92;
"DQ<25>"
$PN"183"93;
"DQ<30>"
$PN"43"98;
"DQ<31>"
$PN"188"99;
"DQ<32>"
$PN"97"100;
"DQ<33>"
$PN"242"101;
"DQ<34>"
$PN"104"102;
"DQ<37>"
$PN"240"108;
"DQ<39>"
$PN"247"116;
"DQ<40>"
$PN"108"109;
"DQ<41>"
$PN"253"115;
"DQ<42>"
$PN"115"110;
"DQ<43>"
$PN"260"114;
"DQ<44>"
$PN"106"113;
"DQ<45>"
$PN"251"111;
"DQ<46>"
$PN"113"112;
"DQ<55>"
$PN"269"122;
"DQ<56>"
$PN"130"123;
"DQ<59>"
$PN"282"139;
"DQ<60>"
$PN"128"140;
"CKE<1>"
$PN"203"46;
"CK0N"
$PN"75"66;
"CB<0>"
$PN"49"25;
"CB<1>"
$PN"194"47;
"CB<2>"
$PN"56"48;
"CB<3>"
$PN"201"49;
"CB<4>"
$PN"47"50;
"CB<5>"
$PN"192"51;
"CB<6>"
$PN"54"52;
"A9"
$PN"66"53;
"A8"
$PN"68"54;
"A7"
$PN"211"55;
"A6"
$PN"69"56;
"A5"
$PN"213"57;
"A4"
$PN"214"58;
"A3"
$PN"71"59;
"A17"
$PN"234"131;
"A13"
$PN"232"132;
"A12"
$PN"65"133;
"A1"
$PN"72"60;
"A0"
$PN"79"61;
"C<2>"
$PN"235"69;
"DQ<28>"
$PN"36"103;
"DQ<29>"
$PN"181"104;
"S1_N"
$PN"89"62;
"S2_N_C<0>"
$PN"93"63;
"S3_N_C<1>"
$PN"237"64;
"CK0P"
$PN"74"67;
"CK1N"
$PN"219"68;
"BA<1>"
$PN"224"65;
%"TAP"
"6","(-3125,4425)","0","mstr_standard","I112";
;
HDL_TAP"TRUE"
BODY_TYPE"PLUMBING"
CDS_LIB"mstr_standard";
"B \NAC \NWC"7;
"S \NAC"
BN"17"131;
%"TAP"
"6","(-3125,4375)","0","mstr_standard","I113";
;
HDL_TAP"TRUE"
BODY_TYPE"PLUMBING"
CDS_LIB"mstr_standard";
"B \NAC \NWC"7;
"S \NAC"
BN"16"127;
%"TAP"
"6","(-3125,4325)","0","mstr_standard","I114";
;
HDL_TAP"TRUE"
BODY_TYPE"PLUMBING"
CDS_LIB"mstr_standard";
"B \NAC \NWC"7;
"S \NAC"
BN"15"128;
%"TAP"
"6","(-3125,4275)","0","mstr_standard","I115";
;
HDL_TAP"TRUE"
BODY_TYPE"PLUMBING"
CDS_LIB"mstr_standard";
"B \NAC \NWC"7;
"S \NAC"
BN"14"129;
%"TAP"
"6","(-3125,4125)","0","mstr_standard","I116";
;
HDL_TAP"TRUE"
BODY_TYPE"PLUMBING"
CDS_LIB"mstr_standard";
"B \NAC \NWC"7;
"S \NAC"
BN"11"130;
%"TAP"
"6","(-3125,4225)","0","mstr_standard","I117";
;
HDL_TAP"TRUE"
BODY_TYPE"PLUMBING"
CDS_LIB"mstr_standard";
"B \NAC \NWC"7;
"S \NAC"
BN"13"132;
%"TAP"
"6","(-3125,4175)","0","mstr_standard","I118";
;
HDL_TAP"TRUE"
BODY_TYPE"PLUMBING"
CDS_LIB"mstr_standard";
"B \NAC \NWC"7;
"S \NAC"
BN"12"133;
%"TAP"
"6","(-3125,4075)","0","mstr_standard","I119";
;
HDL_TAP"TRUE"
BODY_TYPE"PLUMBING"
CDS_LIB"mstr_standard";
"B \NAC \NWC"7;
"S \NAC"
BN"10"40;
%"TAP"
"6","(700,4950)","2","mstr_standard","I12";
;
HDL_TAP"TRUE"
BODY_TYPE"PLUMBING"
CDS_LIB"mstr_standard";
"B \NAC \NWC"2;
"S \NAC"
BN"16"163;
%"TAP"
"6","(-3125,4025)","0","mstr_standard","I120";
;
HDL_TAP"TRUE"
BODY_TYPE"PLUMBING"
CDS_LIB"mstr_standard";
"B \NAC \NWC"7;
"S \NAC"
BN"9"53;
%"TAP"
"6","(-3125,3875)","0","mstr_standard","I121";
;
HDL_TAP"TRUE"
BODY_TYPE"PLUMBING"
CDS_LIB"mstr_standard";
"B \NAC \NWC"7;
"S \NAC"
BN"6"56;
%"TAP"
"6","(-3125,3975)","0","mstr_standard","I122";
;
HDL_TAP"TRUE"
BODY_TYPE"PLUMBING"
CDS_LIB"mstr_standard";
"B \NAC \NWC"7;
"S \NAC"
BN"8"54;
%"TAP"
"6","(-3125,3925)","0","mstr_standard","I123";
;
HDL_TAP"TRUE"
BODY_TYPE"PLUMBING"
CDS_LIB"mstr_standard";
"B \NAC \NWC"7;
"S \NAC"
BN"7"55;
%"TAP"
"6","(-3125,3825)","0","mstr_standard","I124";
;
HDL_TAP"TRUE"
BODY_TYPE"PLUMBING"
CDS_LIB"mstr_standard";
"B \NAC \NWC"7;
"S \NAC"
BN"5"57;
%"TAP"
"6","(-3125,3775)","0","mstr_standard","I125";
;
HDL_TAP"TRUE"
BODY_TYPE"PLUMBING"
CDS_LIB"mstr_standard";
"B \NAC \NWC"7;
"S \NAC"
BN"4"58;
%"TAP"
"6","(-3125,3725)","0","mstr_standard","I126";
;
HDL_TAP"TRUE"
BODY_TYPE"PLUMBING"
CDS_LIB"mstr_standard";
"B \NAC \NWC"7;
"S \NAC"
BN"3"59;
%"TAP"
"6","(-3125,3675)","0","mstr_standard","I127";
;
HDL_TAP"TRUE"
BODY_TYPE"PLUMBING"
CDS_LIB"mstr_standard";
"B \NAC \NWC"7;
"S \NAC"
BN"2"41;
%"TAP"
"6","(-3125,3625)","0","mstr_standard","I128";
;
HDL_TAP"TRUE"
BODY_TYPE"PLUMBING"
CDS_LIB"mstr_standard";
"B \NAC \NWC"7;
"S \NAC"
BN"1"60;
%"TAP"
"6","(-3125,3575)","0","mstr_standard","I129";
;
HDL_TAP"TRUE"
BODY_TYPE"PLUMBING"
CDS_LIB"mstr_standard";
"B \NAC \NWC"7;
"S \NAC"
BN"0"61;
%"TAP"
"6","(700,4450)","2","mstr_standard","I13";
;
HDL_TAP"TRUE"
BODY_TYPE"PLUMBING"
CDS_LIB"mstr_standard";
"B \NAC \NWC"2;
"S \NAC"
BN"11"173;
%"TAP"
"6","(-3125,3475)","0","mstr_standard","I130";
;
HDL_TAP"TRUE"
BODY_TYPE"PLUMBING"
CDS_LIB"mstr_standard";
"B \NAC \NWC"10;
"S \NAC"
BN"1"65;
%"TAP"
"6","(-3125,3425)","0","mstr_standard","I133";
;
HDL_TAP"TRUE"
BODY_TYPE"PLUMBING"
CDS_LIB"mstr_standard";
"B \NAC \NWC"10;
"S \NAC"
BN"0"42;
%"TAP"
"6","(-3125,3375)","0","mstr_standard","I134";
;
HDL_TAP"TRUE"
BODY_TYPE"PLUMBING"
CDS_LIB"mstr_standard";
"B \NAC \NWC"9;
"S \NAC"
BN"1"43;
%"TAP"
"6","(-3125,3325)","0","mstr_standard","I135";
;
HDL_TAP"TRUE"
BODY_TYPE"PLUMBING"
CDS_LIB"mstr_standard";
"B \NAC \NWC"9;
"S \NAC"
BN"0"44;
%"TAP"
"6","(-3125,2375)","0","mstr_standard","I138";
;
HDL_TAP"TRUE"
BODY_TYPE"PLUMBING"
CDS_LIB"mstr_standard";
"B \NAC \NWC"8;
"S \NAC"
BN"6"39;
%"TAP"
"6","(-3125,2325)","0","mstr_standard","I139";
;
HDL_TAP"TRUE"
BODY_TYPE"PLUMBING"
CDS_LIB"mstr_standard";
"B \NAC \NWC"8;
"S \NAC"
BN"7"52;
%"TAP"
"6","(700,4550)","2","mstr_standard","I14";
;
HDL_TAP"TRUE"
BODY_TYPE"PLUMBING"
CDS_LIB"mstr_standard";
"B \NAC \NWC"2;
"S \NAC"
BN"12"171;
%"TAP"
"6","(-3125,2275)","0","mstr_standard","I140";
;
HDL_TAP"TRUE"
BODY_TYPE"PLUMBING"
CDS_LIB"mstr_standard";
"B \NAC \NWC"8;
"S \NAC"
BN"4"51;
%"TAP"
"6","(-3125,2225)","0","mstr_standard","I141";
;
HDL_TAP"TRUE"
BODY_TYPE"PLUMBING"
CDS_LIB"mstr_standard";
"B \NAC \NWC"8;
"S \NAC"
BN"5"50;
%"TAP"
"6","(-3125,2075)","0","mstr_standard","I142";
;
HDL_TAP"TRUE"
BODY_TYPE"PLUMBING"
CDS_LIB"mstr_standard";
"B \NAC \NWC"8;
"S \NAC"
BN"0"47;
%"TAP"
"6","(-3125,2125)","0","mstr_standard","I143";
;
HDL_TAP"TRUE"
BODY_TYPE"PLUMBING"
CDS_LIB"mstr_standard";
"B \NAC \NWC"8;
"S \NAC"
BN"3"48;
%"TAP"
"6","(-3125,2175)","0","mstr_standard","I144";
;
HDL_TAP"TRUE"
BODY_TYPE"PLUMBING"
CDS_LIB"mstr_standard";
"B \NAC \NWC"8;
"S \NAC"
BN"2"49;
%"TAP"
"6","(-3125,2025)","0","mstr_standard","I145";
;
HDL_TAP"TRUE"
BODY_TYPE"PLUMBING"
CDS_LIB"mstr_standard";
"B \NAC \NWC"8;
"S \NAC"
BN"1"25;
%"TAP"
"6","(700,4650)","2","mstr_standard","I15";
;
HDL_TAP"TRUE"
BODY_TYPE"PLUMBING"
CDS_LIB"mstr_standard";
"B \NAC \NWC"2;
"S \NAC"
BN"13"169;
%"TAP"
"6","(-3125,3225)","0","mstr_standard","I152";
;
HDL_TAP"TRUE"
BODY_TYPE"PLUMBING"
CDS_LIB"mstr_standard";
"B \NAC \NWC"4;
"S \NAC"
BN"1"45;
%"TAP"
"6","(-3125,3125)","0","mstr_standard","I153";
;
HDL_TAP"TRUE"
BODY_TYPE"PLUMBING"
CDS_LIB"mstr_standard";
"B \NAC \NWC"4;
"S \NAC"
BN"0"67;
%"TAP"
"6","(-3325,3175)","0","mstr_standard","I156";
;
HDL_TAP"TRUE"
BODY_TYPE"PLUMBING"
CDS_LIB"mstr_standard";
"B \NAC \NWC"5;
"S \NAC"
BN"1"68;
%"TAP"
"6","(-3325,3075)","0","mstr_standard","I157";
;
HDL_TAP"TRUE"
BODY_TYPE"PLUMBING"
CDS_LIB"mstr_standard";
"B \NAC \NWC"5;
"S \NAC"
BN"0"66;
%"TAP"
"6","(-3125,2925)","0","mstr_standard","I158";
;
HDL_TAP"TRUE"
BODY_TYPE"PLUMBING"
CDS_LIB"mstr_standard";
"B \NAC \NWC"6;
"S \NAC"
BN"3"64;
%"TAP"
"6","(-3125,2875)","0","mstr_standard","I159";
;
HDL_TAP"TRUE"
BODY_TYPE"PLUMBING"
CDS_LIB"mstr_standard";
"B \NAC \NWC"6;
"S \NAC"
BN"2"63;
%"PVDDQ_GHJ"
"1","(-1350,2500)","0","mstr_symbols","I16";
;
HDL_POWER"PVDDQ_GHJ"
ROOM"DDR4_CH_G"
BODY_TYPE"PLUMBING"
CDS_LIB"mstr_symbols"
BOM_COST"MEM"
VOLTAGE"1.2V";
"G\NAC"13;
%"TAP"
"6","(-3125,2825)","0","mstr_standard","I160";
;
HDL_TAP"TRUE"
BODY_TYPE"PLUMBING"
CDS_LIB"mstr_standard";
"B \NAC \NWC"6;
"S \NAC"
BN"1"62;
%"TAP"
"6","(-3125,2775)","0","mstr_standard","I161";
;
HDL_TAP"TRUE"
BODY_TYPE"PLUMBING"
CDS_LIB"mstr_standard";
"B \NAC \NWC"6;
"S \NAC"
BN"0"35;
%"TAP"
"6","(-3125,2675)","0","mstr_standard","I162";
;
HDL_TAP"TRUE"
BODY_TYPE"PLUMBING"
CDS_LIB"mstr_standard";
"B \NAC \NWC"12;
"S \NAC"
BN"1"46;
%"TAP"
"6","(-3125,2625)","0","mstr_standard","I165";
;
HDL_TAP"TRUE"
BODY_TYPE"PLUMBING"
CDS_LIB"mstr_standard";
"B \NAC \NWC"12;
"S \NAC"
BN"0"36;
%"TAP"
"6","(-3125,2525)","0","mstr_standard","I166";
;
HDL_TAP"TRUE"
BODY_TYPE"PLUMBING"
CDS_LIB"mstr_standard";
"B \NAC \NWC"11;
"S \NAC"
BN"1"37;
%"TAP"
"6","(-3125,2475)","0","mstr_standard","I168";
;
HDL_TAP"TRUE"
BODY_TYPE"PLUMBING"
CDS_LIB"mstr_standard";
"B \NAC \NWC"11;
"S \NAC"
BN"0"38;
%"PVTT_GHJ"
"1","(-1150,2650)","0","mstr_symbols","I17";
;
HDL_POWER"PVTT_GHJ"
ROOM"DDR4_CH_G"
BODY_TYPE"PLUMBING"
CDS_LIB"mstr_symbols"
BOM_COST"MEM"
VOLTAGE"0.6V";
"G\NAC"14;
%"SCONN288_H44441004"
"4","(-300,1950)","0","mstr_sconn","I171";
;
CDS_SEC"4"
ROOM"DDR4_CH_G"
CDS_LOCATION"J1G1"
SEC"4"
SEC_TYPE"PIP"
CDS_LIB"mstr_sconn"
BOM_COST"MEM"
PACK_TYPE"PIP"
MATERIAL"SCONN"
PART_NUMBER"H44441-004"
LOCATION"J1G1";
"VPP<4>"
$PN"142"18;
"VTT<1>"
$PN"77"14;
"VPP<0>"
$PN"287"18;
"VPP<1>"
$PN"286"18;
"VPP<2>"
$PN"288"18;
"VPP<3>"
$PN"143"18;
"VDD<1>"
$PN"233"13;
"VDD<2>"
$PN"231"13;
"VDD<3>"
$PN"229"13;
"VDD<4>"
$PN"226"13;
"VDD<5>"
$PN"223"13;
"VDD<7>"
$PN"217"13;
"VDD<8>"
$PN"215"13;
"VDD<9>"
$PN"212"13;
"VDD<11>"
$PN"206"13;
"VDD<12>"
$PN"204"13;
"VDD<14>"
$PN"90"13;
"VDD<15>"
$PN"88"13;
"VDD<17>"
$PN"83"13;
"VDD<18>"
$PN"80"13;
"VDD<20>"
$PN"73"13;
"VDD<21>"
$PN"70"13;
"VDD<22>"
$PN"67"13;
"VDD<24>"
$PN"61"13;
"12V<0>"
$PN"145"20;
"12V<1>"
$PN"1"20;
"VTT<0>"
$PN"221"14;
"VDD<25>"
$PN"59"13;
"VDD<23>"
$PN"64"13;
"VDD<19>"
$PN"76"13;
"VDD<16>"
$PN"85"13;
"VDD<13>"
$PN"92"13;
"VDD<10>"
$PN"209"13;
"VDD<6>"
$PN"220"13;
"VDD<0>"
$PN"236"13;
%"GND"
"1","(2500,900)","2","mstr_symbols","I172";
;
HDL_POWER"GND"
ROOM"DDR4_CH_G"
BODY_TYPE"PLUMBING"
BOM_COST"MEM"
CDS_LIB"mstr_symbols"
SIZE"1B"
VOLTAGE"0";
"A\NAC"15;
%"GND"
"1","(-5075,1425)","2","mstr_symbols","I177";
;
HDL_POWER"GND"
ROOM"DDR4_CH_G"
BODY_TYPE"PLUMBING"
BOM_COST"MEM"
CDS_LIB"mstr_symbols"
SIZE"1B"
VOLTAGE"0";
"A\NAC"16;
%"GND"
"1","(-4425,825)","0","mstr_symbols","I180";
;
HDL_POWER"GND"
ROOM"DDR4_CH_G"
BODY_TYPE"PLUMBING"
BOM_COST"MEM"
CDS_LIB"mstr_symbols"
SIZE"1B"
VOLTAGE"0";
"A\NAC"17;
%"CAP_A"
"1","(-4425,1075)","2","dev_discrete","I181";
;
ROOM"DDR4_CH_G"
$SEC"1"
CDS_SEC"1"
CDS_LIB"dev_discrete"
BOM_COST"MEM"
CDS_LOCATION"C1F22"
MATERIAL"X7R"
VOLTAGE"25V"
PACK_TYPE"0402V"
TOLERANCE"10%"
VALUE"0.01UF"
PART_NUMBER"A36096-045"
LOCATION"C1F22";
"B"
$PN"2"17;
"A"
$PN"1"22;
%"PVPP_GHJ"
"1","(-1000,2950)","0","mstr_symbols","I182";
;
HDL_POWER"PVPP_GHJ"
ROOM"DDR4_CH_G"
BODY_TYPE"PLUMBING"
CDS_LIB"mstr_symbols"
BOM_COST"MEM"
VOLTAGE"2.5V";
"G\NAC"18;
%"PVPP_GHJ"
"1","(-5075,1775)","0","mstr_symbols","I183";
;
HDL_POWER"PVPP_GHJ"
ROOM"DDR4_CH_H"
BODY_TYPE"PLUMBING"
CDS_LIB"mstr_symbols"
BOM_COST"MEM"
VOLTAGE"2.5V";
"G\NAC"19;
%"TAP"
"6","(900,4400)","2","mstr_standard","I19";
;
HDL_TAP"TRUE"
BODY_TYPE"PLUMBING"
CDS_LIB"mstr_standard";
"B \NAC \NWC"1;
"S \NAC"
BN"11"174;
%"P12V_NVDIMM_GHJ"
"1","(400,2925)","0","mstr_symbols","I197";
;
HDL_POWER"P12V_NVDIMM_GHJ"
BODY_TYPE"PLUMBING"
CDS_LIB"mstr_symbols"
VOLTAGE"12.0";
"G\NAC"20;
%"TAP"
"6","(900,4200)","2","mstr_standard","I20";
;
HDL_TAP"TRUE"
BODY_TYPE"PLUMBING"
CDS_LIB"mstr_standard";
"B \NAC \NWC"1;
"S \NAC"
BN"9"159;
%"TAP"
"6","(900,4300)","2","mstr_standard","I21";
;
HDL_TAP"TRUE"
BODY_TYPE"PLUMBING"
CDS_LIB"mstr_standard";
"B \NAC \NWC"1;
"S \NAC"
BN"10"176;
%"TAP"
"6","(900,4100)","2","mstr_standard","I22";
;
HDL_TAP"TRUE"
BODY_TYPE"PLUMBING"
CDS_LIB"mstr_standard";
"B \NAC \NWC"1;
"S \NAC"
BN"8"161;
%"TAP"
"6","(900,4000)","2","mstr_standard","I23";
;
HDL_TAP"TRUE"
BODY_TYPE"PLUMBING"
CDS_LIB"mstr_standard";
"B \NAC \NWC"1;
"S \NAC"
BN"7"142;
%"TAP"
"6","(700,4350)","2","mstr_standard","I24";
;
HDL_TAP"TRUE"
BODY_TYPE"PLUMBING"
CDS_LIB"mstr_standard";
"B \NAC \NWC"2;
"S \NAC"
BN"10"175;
%"TAP"
"6","(700,4250)","2","mstr_standard","I25";
;
HDL_TAP"TRUE"
BODY_TYPE"PLUMBING"
CDS_LIB"mstr_standard";
"B \NAC \NWC"2;
"S \NAC"
BN"9"158;
%"TAP"
"6","(700,3950)","2","mstr_standard","I26";
;
HDL_TAP"TRUE"
BODY_TYPE"PLUMBING"
CDS_LIB"mstr_standard";
"B \NAC \NWC"2;
"S \NAC"
BN"6"143;
%"TAP"
"6","(700,4050)","2","mstr_standard","I27";
;
HDL_TAP"TRUE"
BODY_TYPE"PLUMBING"
CDS_LIB"mstr_standard";
"B \NAC \NWC"2;
"S \NAC"
BN"7"141;
%"TAP"
"6","(700,4150)","2","mstr_standard","I28";
;
HDL_TAP"TRUE"
BODY_TYPE"PLUMBING"
CDS_LIB"mstr_standard";
"B \NAC \NWC"2;
"S \NAC"
BN"8"160;
%"TAP"
"6","(900,3900)","2","mstr_standard","I29";
;
HDL_TAP"TRUE"
BODY_TYPE"PLUMBING"
CDS_LIB"mstr_standard";
"B \NAC \NWC"1;
"S \NAC"
BN"6"144;
%"TAP"
"6","(900,5000)","2","mstr_standard","I3";
;
HDL_TAP"TRUE"
BODY_TYPE"PLUMBING"
CDS_LIB"mstr_standard";
"B \NAC \NWC"1;
"S \NAC"
BN"17"162;
%"TAP"
"6","(900,3700)","2","mstr_standard","I30";
;
HDL_TAP"TRUE"
BODY_TYPE"PLUMBING"
CDS_LIB"mstr_standard";
"B \NAC \NWC"1;
"S \NAC"
BN"4"148;
%"TAP"
"6","(900,3800)","2","mstr_standard","I31";
;
HDL_TAP"TRUE"
BODY_TYPE"PLUMBING"
CDS_LIB"mstr_standard";
"B \NAC \NWC"1;
"S \NAC"
BN"5"146;
%"TAP"
"6","(900,3500)","2","mstr_standard","I32";
;
HDL_TAP"TRUE"
BODY_TYPE"PLUMBING"
CDS_LIB"mstr_standard";
"B \NAC \NWC"1;
"S \NAC"
BN"2"152;
%"TAP"
"6","(900,3600)","2","mstr_standard","I33";
;
HDL_TAP"TRUE"
BODY_TYPE"PLUMBING"
CDS_LIB"mstr_standard";
"B \NAC \NWC"1;
"S \NAC"
BN"3"150;
%"TAP"
"6","(700,3750)","2","mstr_standard","I34";
;
HDL_TAP"TRUE"
BODY_TYPE"PLUMBING"
CDS_LIB"mstr_standard";
"B \NAC \NWC"2;
"S \NAC"
BN"4"147;
%"TAP"
"6","(700,3850)","2","mstr_standard","I35";
;
HDL_TAP"TRUE"
BODY_TYPE"PLUMBING"
CDS_LIB"mstr_standard";
"B \NAC \NWC"2;
"S \NAC"
BN"5"145;
%"TAP"
"6","(700,3550)","2","mstr_standard","I36";
;
HDL_TAP"TRUE"
BODY_TYPE"PLUMBING"
CDS_LIB"mstr_standard";
"B \NAC \NWC"2;
"S \NAC"
BN"2"151;
%"TAP"
"6","(700,3450)","2","mstr_standard","I37";
;
HDL_TAP"TRUE"
BODY_TYPE"PLUMBING"
CDS_LIB"mstr_standard";
"B \NAC \NWC"2;
"S \NAC"
BN"1"153;
%"TAP"
"6","(700,3650)","2","mstr_standard","I38";
;
HDL_TAP"TRUE"
BODY_TYPE"PLUMBING"
CDS_LIB"mstr_standard";
"B \NAC \NWC"2;
"S \NAC"
BN"3"149;
%"TAP"
"6","(900,3300)","2","mstr_standard","I39";
;
HDL_TAP"TRUE"
BODY_TYPE"PLUMBING"
CDS_LIB"mstr_standard";
"B \NAC \NWC"1;
"S \NAC"
BN"0"156;
%"TAP"
"6","(700,5050)","2","mstr_standard","I4";
;
HDL_TAP"TRUE"
BODY_TYPE"PLUMBING"
CDS_LIB"mstr_standard";
"B \NAC \NWC"2;
"S \NAC"
BN"17"157;
%"TAP"
"6","(900,3400)","2","mstr_standard","I40";
;
HDL_TAP"TRUE"
BODY_TYPE"PLUMBING"
CDS_LIB"mstr_standard";
"B \NAC \NWC"1;
"S \NAC"
BN"1"154;
%"TAP"
"6","(700,3350)","2","mstr_standard","I41";
;
HDL_TAP"TRUE"
BODY_TYPE"PLUMBING"
CDS_LIB"mstr_standard";
"B \NAC \NWC"2;
"S \NAC"
BN"0"155;
%"SCONN288_H44441004"
"3","(1800,2200)","0","mstr_sconn","I43";
;
CDS_SEC"3"
ROOM"DDR4_CH_G"
CDS_LOCATION"J1G1"
SEC"3"
SEC_TYPE"PIP"
CDS_LIB"mstr_sconn"
BOM_COST"MEM"
PACK_TYPE"PIP"
MATERIAL"SCONN"
PART_NUMBER"H44441-004"
LOCATION"J1G1";
"VSS<93>"
$PN"2"21;
"VSS<92>"
$PN"4"21;
"VSS<91>"
$PN"6"21;
"VSS<90>"
$PN"9"21;
"VSS<89>"
$PN"11"21;
"VSS<88>"
$PN"13"21;
"VSS<0>"
$PN"283"15;
"VSS<1>"
$PN"281"15;
"VSS<2>"
$PN"279"15;
"VSS<3>"
$PN"276"15;
"VSS<4>"
$PN"274"15;
"VSS<5>"
$PN"272"15;
"VSS<6>"
$PN"270"15;
"VSS<7>"
$PN"268"15;
"VSS<8>"
$PN"265"15;
"VSS<9>"
$PN"263"15;
"VSS<10>"
$PN"261"15;
"VSS<11>"
$PN"259"15;
"VSS<12>"
$PN"257"15;
"VSS<13>"
$PN"254"15;
"VSS<14>"
$PN"252"15;
"VSS<15>"
$PN"250"15;
"VSS<16>"
$PN"248"15;
"VSS<17>"
$PN"246"15;
"VSS<18>"
$PN"243"15;
"VSS<19>"
$PN"241"15;
"VSS<20>"
$PN"239"15;
"VSS<21>"
$PN"202"15;
"VSS<22>"
$PN"200"15;
"VSS<23>"
$PN"198"15;
"VSS<24>"
$PN"195"15;
"VSS<25>"
$PN"193"15;
"VSS<26>"
$PN"191"15;
"VSS<27>"
$PN"189"15;
"VSS<28>"
$PN"187"15;
"VSS<29>"
$PN"184"15;
"VSS<30>"
$PN"182"15;
"VSS<31>"
$PN"180"15;
"VSS<32>"
$PN"178"15;
"VSS<33>"
$PN"176"15;
"VSS<34>"
$PN"173"15;
"VSS<35>"
$PN"171"15;
"VSS<36>"
$PN"169"15;
"VSS<37>"
$PN"167"15;
"VSS<38>"
$PN"165"15;
"VSS<39>"
$PN"162"15;
"VSS<40>"
$PN"160"15;
"VSS<41>"
$PN"158"15;
"VSS<42>"
$PN"156"15;
"VSS<43>"
$PN"154"15;
"VSS<44>"
$PN"151"15;
"VSS<47>"
$PN"138"21;
"VSS<48>"
$PN"136"21;
"VSS<49>"
$PN"134"21;
"VSS<50>"
$PN"131"21;
"VSS<51>"
$PN"129"21;
"VSS<52>"
$PN"127"21;
"VSS<53>"
$PN"125"21;
"VSS<54>"
$PN"123"21;
"VSS<55>"
$PN"120"21;
"VSS<56>"
$PN"118"21;
"VSS<57>"
$PN"116"21;
"VSS<58>"
$PN"114"21;
"VSS<59>"
$PN"112"21;
"VSS<60>"
$PN"109"21;
"VSS<61>"
$PN"107"21;
"VSS<62>"
$PN"105"21;
"VSS<63>"
$PN"103"21;
"VSS<64>"
$PN"101"21;
"VSS<65>"
$PN"98"21;
"VSS<66>"
$PN"96"21;
"VSS<67>"
$PN"94"21;
"VSS<68>"
$PN"57"21;
"VSS<69>"
$PN"55"21;
"VSS<70>"
$PN"53"21;
"VSS<71>"
$PN"50"21;
"VSS<72>"
$PN"48"21;
"VSS<73>"
$PN"46"21;
"VSS<74>"
$PN"44"21;
"VSS<75>"
$PN"42"21;
"VSS<76>"
$PN"39"21;
"VSS<77>"
$PN"37"21;
"VSS<78>"
$PN"35"21;
"VSS<79>"
$PN"33"21;
"VSS<80>"
$PN"31"21;
"VSS<81>"
$PN"28"21;
"VSS<82>"
$PN"26"21;
"VSS<83>"
$PN"24"21;
"VSS<84>"
$PN"22"21;
"VSS<85>"
$PN"20"21;
"VSS<86>"
$PN"17"21;
"VSS<87>"
$PN"15"21;
"VSS<45>"
$PN"149"15;
"VSS<46>"
$PN"147"15;
%"GND"
"1","(1100,900)","2","mstr_symbols","I44";
;
HDL_POWER"GND"
ROOM"DDR4_CH_G"
BODY_TYPE"PLUMBING"
BOM_COST"MEM"
CDS_LIB"mstr_symbols"
SIZE"1B"
VOLTAGE"0";
"A\NAC"21;
%"TAP"
"6","(-1625,4375)","2","mstr_standard","I46";
;
HDL_TAP"TRUE"
BODY_TYPE"PLUMBING"
CDS_LIB"mstr_standard";
"B \NAC \NWC"3;
"S \NAC"
BN"63"135;
%"TAP"
"6","(-1625,4425)","2","mstr_standard","I47";
;
HDL_TAP"TRUE"
BODY_TYPE"PLUMBING"
CDS_LIB"mstr_standard";
"B \NAC \NWC"3;
"S \NAC"
BN"62"134;
%"TAP"
"6","(-1625,4275)","2","mstr_standard","I48";
;
HDL_TAP"TRUE"
BODY_TYPE"PLUMBING"
CDS_LIB"mstr_standard";
"B \NAC \NWC"3;
"S \NAC"
BN"61"140;
%"TAP"
"6","(-1625,4325)","2","mstr_standard","I49";
;
HDL_TAP"TRUE"
BODY_TYPE"PLUMBING"
CDS_LIB"mstr_standard";
"B \NAC \NWC"3;
"S \NAC"
BN"60"136;
%"TAP"
"6","(900,4800)","2","mstr_standard","I5";
;
HDL_TAP"TRUE"
BODY_TYPE"PLUMBING"
CDS_LIB"mstr_standard";
"B \NAC \NWC"1;
"S \NAC"
BN"15"166;
%"TAP"
"6","(-1625,4225)","2","mstr_standard","I50";
;
HDL_TAP"TRUE"
BODY_TYPE"PLUMBING"
CDS_LIB"mstr_standard";
"B \NAC \NWC"3;
"S \NAC"
BN"58"139;
%"TAP"
"6","(-1625,4175)","2","mstr_standard","I51";
;
HDL_TAP"TRUE"
BODY_TYPE"PLUMBING"
CDS_LIB"mstr_standard";
"B \NAC \NWC"3;
"S \NAC"
BN"59"137;
%"TAP"
"6","(-1625,4125)","2","mstr_standard","I52";
;
HDL_TAP"TRUE"
BODY_TYPE"PLUMBING"
CDS_LIB"mstr_standard";
"B \NAC \NWC"3;
"S \NAC"
BN"56"138;
%"TAP"
"6","(-1625,4075)","2","mstr_standard","I53";
;
HDL_TAP"TRUE"
BODY_TYPE"PLUMBING"
CDS_LIB"mstr_standard";
"B \NAC \NWC"3;
"S \NAC"
BN"57"123;
%"TAP"
"6","(-1625,4025)","2","mstr_standard","I54";
;
HDL_TAP"TRUE"
BODY_TYPE"PLUMBING"
CDS_LIB"mstr_standard";
"B \NAC \NWC"3;
"S \NAC"
BN"54"122;
%"TAP"
"6","(-1625,3875)","2","mstr_standard","I55";
;
HDL_TAP"TRUE"
BODY_TYPE"PLUMBING"
CDS_LIB"mstr_standard";
"B \NAC \NWC"3;
"S \NAC"
BN"53"119;
%"TAP"
"6","(-1625,3975)","2","mstr_standard","I56";
;
HDL_TAP"TRUE"
BODY_TYPE"PLUMBING"
CDS_LIB"mstr_standard";
"B \NAC \NWC"3;
"S \NAC"
BN"55"121;
%"TAP"
"6","(-1625,3925)","2","mstr_standard","I57";
;
HDL_TAP"TRUE"
BODY_TYPE"PLUMBING"
CDS_LIB"mstr_standard";
"B \NAC \NWC"3;
"S \NAC"
BN"52"120;
%"TAP"
"6","(-1625,3825)","2","mstr_standard","I58";
;
HDL_TAP"TRUE"
BODY_TYPE"PLUMBING"
CDS_LIB"mstr_standard";
"B \NAC \NWC"3;
"S \NAC"
BN"50"118;
%"TAP"
"6","(-1625,3775)","2","mstr_standard","I59";
;
HDL_TAP"TRUE"
BODY_TYPE"PLUMBING"
CDS_LIB"mstr_standard";
"B \NAC \NWC"3;
"S \NAC"
BN"51"124;
%"TAP"
"6","(900,4900)","2","mstr_standard","I6";
;
HDL_TAP"TRUE"
BODY_TYPE"PLUMBING"
CDS_LIB"mstr_standard";
"B \NAC \NWC"1;
"S \NAC"
BN"16"164;
%"TAP"
"6","(-1625,3725)","2","mstr_standard","I60";
;
HDL_TAP"TRUE"
BODY_TYPE"PLUMBING"
CDS_LIB"mstr_standard";
"B \NAC \NWC"3;
"S \NAC"
BN"48"125;
%"TAP"
"6","(-1625,3575)","2","mstr_standard","I61";
;
HDL_TAP"TRUE"
BODY_TYPE"PLUMBING"
CDS_LIB"mstr_standard";
"B \NAC \NWC"3;
"S \NAC"
BN"47"112;
%"TAP"
"6","(-1625,3675)","2","mstr_standard","I62";
;
HDL_TAP"TRUE"
BODY_TYPE"PLUMBING"
CDS_LIB"mstr_standard";
"B \NAC \NWC"3;
"S \NAC"
BN"49"126;
%"TAP"
"6","(-1625,3625)","2","mstr_standard","I63";
;
HDL_TAP"TRUE"
BODY_TYPE"PLUMBING"
CDS_LIB"mstr_standard";
"B \NAC \NWC"3;
"S \NAC"
BN"46"117;
%"TAP"
"6","(-1625,3525)","2","mstr_standard","I64";
;
HDL_TAP"TRUE"
BODY_TYPE"PLUMBING"
CDS_LIB"mstr_standard";
"B \NAC \NWC"3;
"S \NAC"
BN"44"111;
%"TAP"
"6","(-1625,3475)","2","mstr_standard","I65";
;
HDL_TAP"TRUE"
BODY_TYPE"PLUMBING"
CDS_LIB"mstr_standard";
"B \NAC \NWC"3;
"S \NAC"
BN"45"113;
%"SCONN288_H44441004"
"2","(0,4200)","0","mstr_sconn","I66";
;
CDS_SEC"2"
ROOM"DDR4_CH_G"
CDS_LOCATION"J1G1"
SEC"2"
SEC_TYPE"PIP"
CDS_LIB"mstr_sconn"
BOM_COST"MEM"
PACK_TYPE"PIP"
MATERIAL"SCONN"
PART_NUMBER"H44441-004"
LOCATION"J1G1";
"DQS17P"
$PN"51"157;
"DQS9P"
$PN"7"158;
"DQS9N"
$PN"8"159;
"DQS8P"
$PN"197"160;
"DQS8N"
$PN"196"161;
"DQS7P"
$PN"278"141;
"DQS7N"
$PN"277"142;
"DQS6P"
$PN"267"143;
"DQS6N"
$PN"266"144;
"DQS5P"
$PN"256"145;
"DQS5N"
$PN"255"146;
"DQS4P"
$PN"245"147;
"DQS4N"
$PN"244"148;
"DQS3P"
$PN"186"149;
"DQS3N"
$PN"185"150;
"DQS2P"
$PN"175"151;
"DQS2N"
$PN"174"152;
"DQS1P"
$PN"164"153;
"DQS1N"
$PN"163"154;
"DQS17N"
$PN"52"162;
"DQS16P"
$PN"132"163;
"DQS16N"
$PN"133"164;
"DQS15P"
$PN"121"165;
"DQS15N"
$PN"122"166;
"DQS14P"
$PN"110"167;
"DQS14N"
$PN"111"168;
"DQS13P"
$PN"99"169;
"DQS13N"
$PN"100"170;
"DQS12P"
$PN"40"171;
"DQS12N"
$PN"41"172;
"DQS11P"
$PN"29"173;
"DQS11N"
$PN"30"174;
"DQS10P"
$PN"18"175;
"DQS10N"
$PN"19"176;
"DQS0P"
$PN"153"155;
"DQS0N"
$PN"152"156;
%"TAP"
"6","(-1625,3325)","2","mstr_standard","I67";
;
HDL_TAP"TRUE"
BODY_TYPE"PLUMBING"
CDS_LIB"mstr_standard";
"B \NAC \NWC"3;
"S \NAC"
BN"40"115;
%"TAP"
"6","(-1625,3375)","2","mstr_standard","I68";
;
HDL_TAP"TRUE"
BODY_TYPE"PLUMBING"
CDS_LIB"mstr_standard";
"B \NAC \NWC"3;
"S \NAC"
BN"43"110;
%"TAP"
"6","(-1625,3425)","2","mstr_standard","I69";
;
HDL_TAP"TRUE"
BODY_TYPE"PLUMBING"
CDS_LIB"mstr_standard";
"B \NAC \NWC"3;
"S \NAC"
BN"42"114;
%"TAP"
"6","(900,4600)","2","mstr_standard","I7";
;
HDL_TAP"TRUE"
BODY_TYPE"PLUMBING"
CDS_LIB"mstr_standard";
"B \NAC \NWC"1;
"S \NAC"
BN"13"170;
%"TAP"
"6","(-1625,3225)","2","mstr_standard","I70";
;
HDL_TAP"TRUE"
BODY_TYPE"PLUMBING"
CDS_LIB"mstr_standard";
"B \NAC \NWC"3;
"S \NAC"
BN"38"116;
%"TAP"
"6","(-1625,3275)","2","mstr_standard","I71";
;
HDL_TAP"TRUE"
BODY_TYPE"PLUMBING"
CDS_LIB"mstr_standard";
"B \NAC \NWC"3;
"S \NAC"
BN"41"109;
%"TAP"
"6","(-1625,3075)","2","mstr_standard","I72";
;
HDL_TAP"TRUE"
BODY_TYPE"PLUMBING"
CDS_LIB"mstr_standard";
"B \NAC \NWC"3;
"S \NAC"
BN"37"107;
%"TAP"
"6","(-1625,3125)","2","mstr_standard","I73";
;
HDL_TAP"TRUE"
BODY_TYPE"PLUMBING"
CDS_LIB"mstr_standard";
"B \NAC \NWC"3;
"S \NAC"
BN"36"108;
%"TAP"
"6","(-1625,3175)","2","mstr_standard","I74";
;
HDL_TAP"TRUE"
BODY_TYPE"PLUMBING"
CDS_LIB"mstr_standard";
"B \NAC \NWC"3;
"S \NAC"
BN"39"106;
%"TAP"
"6","(-1625,2975)","2","mstr_standard","I75";
;
HDL_TAP"TRUE"
BODY_TYPE"PLUMBING"
CDS_LIB"mstr_standard";
"B \NAC \NWC"3;
"S \NAC"
BN"35"102;
%"TAP"
"6","(-1625,3025)","2","mstr_standard","I76";
;
HDL_TAP"TRUE"
BODY_TYPE"PLUMBING"
CDS_LIB"mstr_standard";
"B \NAC \NWC"3;
"S \NAC"
BN"34"97;
%"TAP"
"6","(-1625,2825)","2","mstr_standard","I77";
;
HDL_TAP"TRUE"
BODY_TYPE"PLUMBING"
CDS_LIB"mstr_standard";
"B \NAC \NWC"3;
"S \NAC"
BN"30"99;
%"TAP"
"6","(-1625,2875)","2","mstr_standard","I78";
;
HDL_TAP"TRUE"
BODY_TYPE"PLUMBING"
CDS_LIB"mstr_standard";
"B \NAC \NWC"3;
"S \NAC"
BN"33"100;
%"TAP"
"6","(-1625,2925)","2","mstr_standard","I79";
;
HDL_TAP"TRUE"
BODY_TYPE"PLUMBING"
CDS_LIB"mstr_standard";
"B \NAC \NWC"3;
"S \NAC"
BN"32"101;
%"TAP"
"6","(900,4700)","2","mstr_standard","I8";
;
HDL_TAP"TRUE"
BODY_TYPE"PLUMBING"
CDS_LIB"mstr_standard";
"B \NAC \NWC"1;
"S \NAC"
BN"14"168;
%"TAP"
"6","(-1625,2775)","2","mstr_standard","I80";
;
HDL_TAP"TRUE"
BODY_TYPE"PLUMBING"
CDS_LIB"mstr_standard";
"B \NAC \NWC"3;
"S \NAC"
BN"31"98;
%"TAP"
"6","(-1625,2725)","2","mstr_standard","I81";
;
HDL_TAP"TRUE"
BODY_TYPE"PLUMBING"
CDS_LIB"mstr_standard";
"B \NAC \NWC"3;
"S \NAC"
BN"28"104;
%"TAP"
"6","(-1625,2575)","2","mstr_standard","I82";
;
HDL_TAP"TRUE"
BODY_TYPE"PLUMBING"
CDS_LIB"mstr_standard";
"B \NAC \NWC"3;
"S \NAC"
BN"27"96;
%"TAP"
"6","(-1625,2675)","2","mstr_standard","I83";
;
HDL_TAP"TRUE"
BODY_TYPE"PLUMBING"
CDS_LIB"mstr_standard";
"B \NAC \NWC"3;
"S \NAC"
BN"29"103;
%"TAP"
"6","(-1625,2625)","2","mstr_standard","I84";
;
HDL_TAP"TRUE"
BODY_TYPE"PLUMBING"
CDS_LIB"mstr_standard";
"B \NAC \NWC"3;
"S \NAC"
BN"26"105;
%"TAP"
"6","(-1625,2475)","2","mstr_standard","I85";
;
HDL_TAP"TRUE"
BODY_TYPE"PLUMBING"
CDS_LIB"mstr_standard";
"B \NAC \NWC"3;
"S \NAC"
BN"25"92;
%"TAP"
"6","(-1625,2525)","2","mstr_standard","I86";
;
HDL_TAP"TRUE"
BODY_TYPE"PLUMBING"
CDS_LIB"mstr_standard";
"B \NAC \NWC"3;
"S \NAC"
BN"24"93;
%"TAP"
"6","(-1625,2325)","2","mstr_standard","I87";
;
HDL_TAP"TRUE"
BODY_TYPE"PLUMBING"
CDS_LIB"mstr_standard";
"B \NAC \NWC"3;
"S \NAC"
BN"20"89;
%"TAP"
"6","(-1625,2425)","2","mstr_standard","I88";
;
HDL_TAP"TRUE"
BODY_TYPE"PLUMBING"
CDS_LIB"mstr_standard";
"B \NAC \NWC"3;
"S \NAC"
BN"22"91;
%"TAP"
"6","(-1625,2375)","2","mstr_standard","I89";
;
HDL_TAP"TRUE"
BODY_TYPE"PLUMBING"
CDS_LIB"mstr_standard";
"B \NAC \NWC"3;
"S \NAC"
BN"23"90;
%"TAP"
"6","(900,4500)","2","mstr_standard","I9";
;
HDL_TAP"TRUE"
BODY_TYPE"PLUMBING"
CDS_LIB"mstr_standard";
"B \NAC \NWC"1;
"S \NAC"
BN"12"172;
%"TAP"
"6","(-1625,2275)","2","mstr_standard","I90";
;
HDL_TAP"TRUE"
BODY_TYPE"PLUMBING"
CDS_LIB"mstr_standard";
"B \NAC \NWC"3;
"S \NAC"
BN"21"88;
%"TAP"
"6","(-1625,2225)","2","mstr_standard","I91";
;
HDL_TAP"TRUE"
BODY_TYPE"PLUMBING"
CDS_LIB"mstr_standard";
"B \NAC \NWC"3;
"S \NAC"
BN"18"87;
%"TAP"
"6","(-1625,2175)","2","mstr_standard","I92";
;
HDL_TAP"TRUE"
BODY_TYPE"PLUMBING"
CDS_LIB"mstr_standard";
"B \NAC \NWC"3;
"S \NAC"
BN"19"86;
%"TAP"
"6","(-1625,2125)","2","mstr_standard","I93";
;
HDL_TAP"TRUE"
BODY_TYPE"PLUMBING"
CDS_LIB"mstr_standard";
"B \NAC \NWC"3;
"S \NAC"
BN"16"95;
%"TAP"
"6","(-1625,2075)","2","mstr_standard","I94";
;
HDL_TAP"TRUE"
BODY_TYPE"PLUMBING"
CDS_LIB"mstr_standard";
"B \NAC \NWC"3;
"S \NAC"
BN"17"94;
%"TAP"
"6","(-1625,2025)","2","mstr_standard","I95";
;
HDL_TAP"TRUE"
BODY_TYPE"PLUMBING"
CDS_LIB"mstr_standard";
"B \NAC \NWC"3;
"S \NAC"
BN"14"76;
%"TAP"
"6","(-1625,1975)","2","mstr_standard","I96";
;
HDL_TAP"TRUE"
BODY_TYPE"PLUMBING"
CDS_LIB"mstr_standard";
"B \NAC \NWC"3;
"S \NAC"
BN"15"84;
%"TAP"
"6","(-1625,1875)","2","mstr_standard","I97";
;
HDL_TAP"TRUE"
BODY_TYPE"PLUMBING"
CDS_LIB"mstr_standard";
"B \NAC \NWC"3;
"S \NAC"
BN"13"82;
%"TAP"
"6","(-1625,1925)","2","mstr_standard","I98";
;
HDL_TAP"TRUE"
BODY_TYPE"PLUMBING"
CDS_LIB"mstr_standard";
"B \NAC \NWC"3;
"S \NAC"
BN"12"83;
%"TAP"
"6","(-1625,1825)","2","mstr_standard","I99";
;
HDL_TAP"TRUE"
BODY_TYPE"PLUMBING"
CDS_LIB"mstr_standard";
"B \NAC \NWC"3;
"S \NAC"
BN"10"81;
END.
